# SCM (Grand Teton) — schematic netlist excerpt (pin names and nets, part order shuffled) for the footprints in the layout excerpt that follows; sources: Cadence DE-HDL packaged netlist, KiCad conversion of 12092022_DA0F0TMDCD0_F0T_Management_Board_D_brd_V3_OCP.brd

R663  Q_RES  10K 1% EMPTY  pkg 0402LF  page 21 : A = P3V3_AUX ; B = EMMC_CMD_R
PC262  Q_CAP  10UF 25V 10% X6S  pkg C0805  page 56 : A = SW_P1V0_AUX_FLT ; B = GND

(kicad_pcb
	(version 20260206)
	(generator "pcbnew")
	(generator_version "10.0")
	(general
		(thickness 1.6)
		(legacy_teardrops no)
	)
	(paper "A4")
	(title_block
		(title "12092022_DA0F0TMDCD0_F0T_Management_Board_D_brd_V3_OCP.brd")
		(comment 1 "Grand Teton / footprints 588-589 of 1440")
	)
	(layers
		(0 "F.Cu" signal "TOP")
		(4 "In1.Cu" signal "GND")
		(6 "In2.Cu" signal "IN1")
		(8 "In3.Cu" signal "GND1")
		(10 "In4.Cu" signal "IN2")
		(12 "In5.Cu" signal "VCC")
		(14 "In6.Cu" signal "VCC1")
		(16 "In7.Cu" signal "IN3")
		(18 "In8.Cu" signal "GND2")
		(20 "In9.Cu" signal "IN4")
		(22 "In10.Cu" signal "GND3")
		(2 "B.Cu" signal "BOTTOM")
		(9 "F.Adhes" user "F.Adhesive")
		(11 "B.Adhes" user "B.Adhesive")
		(13 "F.Paste" user "Package Geometry/Pastemask Top")
		(15 "B.Paste" user "Package Geometry/Pastemask Bottom")
		(5 "F.SilkS" user "Ref Des/Silkscreen Top")
		(7 "B.SilkS" user "Ref Des/Silkscreen Bottom")
		(1 "F.Mask" user "Board Geometry/Soldermask Top")
		(3 "B.Mask" user "Board Geometry/Soldermask Bottom")
		(17 "Dwgs.User" user "User.Drawings")
		(19 "Cmts.User" user "User.Comments")
		(21 "Eco1.User" user "User.Eco1")
		(23 "Eco2.User" user "User.Eco2")
		(25 "Edge.Cuts" user "Board Geometry/Outline")
		(27 "Margin" user)
		(31 "F.CrtYd" user "Package Geometry/Place Bound Top")
		(29 "B.CrtYd" user "Package Geometry/Place Bound Bottom")
		(35 "F.Fab" user "Ref Des/Assembly Top")
		(33 "B.Fab" user "Ref Des/Assembly Bottom")
	)
	(footprint ""
		(layer "F.Cu")
		(at 30.967172 -83.816952 -90)
		(property "Reference" "R663"
			(at 0 0 270)
			(layer "F.SilkS")
			(hide yes)
			(effects
				(font
					(size 1.27 1.27)
				)
			)
		)
		(property "Value" ""
			(at 0 0 270)
			(layer "F.Fab")
			(effects
				(font
					(size 1.27 1.27)
				)
			)
		)
		(duplicate_pad_numbers_are_jumpers no)
		(fp_line
			(start -0.7874 0.4064)
			(end -0.7874 -0.4064)
			(stroke
				(width 0.1524)
				(type default)
			)
			(layer "F.SilkS")
		)
		(fp_line
			(start 0.7874 0.4064)
			(end -0.7874 0.4064)
			(stroke
				(width 0.1524)
				(type default)
			)
			(layer "F.SilkS")
		)
		(fp_line
			(start -0.7874 -0.4064)
			(end 0.7874 -0.4064)
			(stroke
				(width 0.1524)
				(type default)
			)
			(layer "F.SilkS")
		)
		(fp_line
			(start 0.7874 -0.4064)
			(end 0.7874 0.4064)
			(stroke
				(width 0.1524)
				(type default)
			)
			(layer "F.SilkS")
		)
		(fp_line
			(start -0.67945 0.3048)
			(end -0.67945 -0.305054)
			(stroke
				(width 0.1)
				(type default)
			)
			(layer "F.Fab")
		)
		(fp_line
			(start -0.12065 0.3048)
			(end -0.67945 0.3048)
			(stroke
				(width 0.1)
				(type default)
			)
			(layer "F.Fab")
		)
		(fp_line
			(start 0.120396 0.3048)
			(end 0.120396 0.2794)
			(stroke
				(width 0.1)
				(type default)
			)
			(layer "F.Fab")
		)
		(fp_line
			(start 0.67945 0.3048)
			(end 0.120396 0.3048)
			(stroke
				(width 0.1)
				(type default)
			)
			(layer "F.Fab")
		)
		(fp_line
			(start -0.12065 0.2794)
			(end -0.12065 0.3048)
			(stroke
				(width 0.1)
				(type default)
			)
			(layer "F.Fab")
		)
		(fp_line
			(start 0.120396 0.2794)
			(end -0.12065 0.2794)
			(stroke
				(width 0.1)
				(type default)
			)
			(layer "F.Fab")
		)
		(fp_line
			(start -0.12065 -0.2794)
			(end 0.12065 -0.2794)
			(stroke
				(width 0.1)
				(type default)
			)
			(layer "F.Fab")
		)
		(fp_line
			(start 0.12065 -0.2794)
			(end 0.12065 -0.3048)
			(stroke
				(width 0.1)
				(type default)
			)
			(layer "F.Fab")
		)
		(fp_line
			(start 0.12065 -0.3048)
			(end 0.67945 -0.3048)
			(stroke
				(width 0.1)
				(type default)
			)
			(layer "F.Fab")
		)
		(fp_line
			(start 0.67945 -0.3048)
			(end 0.67945 0.3048)
			(stroke
				(width 0.1)
				(type default)
			)
			(layer "F.Fab")
		)
		(fp_line
			(start -0.67945 -0.305054)
			(end -0.12065 -0.305054)
			(stroke
				(width 0.1)
				(type default)
			)
			(layer "F.Fab")
		)
		(fp_line
			(start -0.12065 -0.305054)
			(end -0.12065 -0.2794)
			(stroke
				(width 0.1)
				(type default)
			)
			(layer "F.Fab")
		)
		(pad "1" smd circle
			(at -0.40005 0 270)
			(size 0 0)
			(layers "F.Cu" "F.Mask" "F.Paste")
			(net "P3V3_AUX")
		)
		(pad "2" smd circle
			(at 0.40005 0 270)
			(size 0 0)
			(layers "F.Cu" "F.Mask" "F.Paste")
			(net "EMMC_CMD_R")
		)
	)
	(footprint ""
		(layer "F.Cu")
		(at 19.3421 -37.868352 180)
		(property "Reference" "PC262"
			(at 0 0 180)
			(layer "F.SilkS")
			(hide yes)
			(effects
				(font
					(size 1.27 1.27)
				)
			)
		)
		(property "Value" ""
			(at 0 0 180)
			(layer "F.Fab")
			(effects
				(font
					(size 1.27 1.27)
				)
			)
		)
		(duplicate_pad_numbers_are_jumpers no)
		(fp_line
			(start 1.651 0.8382)
			(end -1.651 0.8382)
			(stroke
				(width 0.1524)
				(type default)
			)
			(layer "F.SilkS")
		)
		(fp_line
			(start 1.651 -0.8382)
			(end 1.651 0.8382)
			(stroke
				(width 0.1524)
				(type default)
			)
			(layer "F.SilkS")
		)
		(fp_line
			(start 0 0.8382)
			(end 0 -0.8382)
			(stroke
				(width 0.1524)
				(type default)
			)
			(layer "F.SilkS")
		)
		(fp_line
			(start -1.651 0.8382)
			(end -1.651 -0.8382)
			(stroke
				(width 0.1524)
				(type default)
			)
			(layer "F.SilkS")
		)
		(fp_line
			(start -1.651 -0.8382)
			(end 1.651 -0.8382)
			(stroke
				(width 0.1524)
				(type default)
			)
			(layer "F.SilkS")
		)
		(fp_line
			(start 1.55956 0.7366)
			(end 1.55956 -0.7366)
			(stroke
				(width 0.1)
				(type default)
			)
			(layer "F.Fab")
		)
		(fp_line
			(start 1.55956 -0.7366)
			(end 1.524 -0.7366)
			(stroke
				(width 0.1)
				(type default)
			)
			(layer "F.Fab")
		)
		(fp_line
			(start 1.524 0.7366)
			(end 1.55956 0.7366)
			(stroke
				(width 0.1)
				(type default)
			)
			(layer "F.Fab")
		)
		(fp_line
			(start 1.524 -0.7366)
			(end -1.524 -0.7366)
			(stroke
				(width 0.1)
				(type default)
			)
			(layer "F.Fab")
		)
		(fp_line
			(start -1.524 0.7366)
			(end 1.524 0.7366)
			(stroke
				(width 0.1)
				(type default)
			)
			(layer "F.Fab")
		)
		(fp_line
			(start -1.524 -0.7366)
			(end -1.55956 -0.7366)
			(stroke
				(width 0.1)
				(type default)
			)
			(layer "F.Fab")
		)
		(fp_line
			(start -1.55956 0.7366)
			(end -1.524 0.7366)
			(stroke
				(width 0.1)
				(type default)
			)
			(layer "F.Fab")
		)
		(fp_line
			(start -1.55956 -0.7366)
			(end -1.55956 0.7366)
			(stroke
				(width 0.1)
				(type default)
			)
			(layer "F.Fab")
		)
		(pad "1" smd rect
			(at -0.94996 0)
			(size 1.1176 1.3716)
			(layers "F.Cu" "F.Mask" "F.Paste")
			(net "SW_P1V0_AUX_FLT")
		)
		(pad "2" smd rect
			(at 0.94996 0)
			(size 1.1176 1.3716)
			(layers "F.Cu" "F.Mask" "F.Paste")
			(net "GND")
		)
	)
)
